# S9S_MB_2U (Grand Teton) — schematic netlist excerpt (pin names and nets, part order shuffled) for the footprints in the layout excerpt that follows; sources: Cadence DE-HDL packaged netlist, KiCad conversion of 03242023_DA0F0TMBIJ0_F0T_Motherboard_J_brd_V01_OCP.brd

C2178  Q_CAP  0.1UF 25V 10% X7R  pkg 0402  page 250 : A = P12V_OCP_SFF_ISENSE_TIC ; B = GND
R1905  Q_RES  1K 1% CHIP  pkg 0402LF  page 156 : A = P3V3_AUX ; B = OCP_SFF_PRSNT0_R_N

(kicad_pcb
	(version 20260206)
	(generator "pcbnew")
	(generator_version "10.0")
	(general
		(thickness 1.6)
		(legacy_teardrops no)
	)
	(paper "A4")
	(title_block
		(title "03242023_DA0F0TMBIJ0_F0T_Motherboard_J_brd_V01_OCP.brd")
		(comment 1 "Grand Teton / footprints 2924-2925 of 6105")
	)
	(layers
		(0 "F.Cu" signal "TOP")
		(4 "In1.Cu" signal "GND")
		(6 "In2.Cu" signal "IN1")
		(8 "In3.Cu" signal "GND1")
		(10 "In4.Cu" signal "IN2")
		(12 "In5.Cu" signal "GND2")
		(14 "In6.Cu" signal "IN3")
		(16 "In7.Cu" signal "GND3")
		(18 "In8.Cu" signal "VCC")
		(20 "In9.Cu" signal "VCC1")
		(22 "In10.Cu" signal "GND4")
		(24 "In11.Cu" signal "IN4")
		(26 "In12.Cu" signal "GND5")
		(28 "In13.Cu" signal "IN5")
		(30 "In14.Cu" signal "GND6")
		(32 "In15.Cu" signal "IN6")
		(34 "In16.Cu" signal "GND7")
		(2 "B.Cu" signal "BOTTOM")
		(9 "F.Adhes" user "F.Adhesive")
		(11 "B.Adhes" user "B.Adhesive")
		(13 "F.Paste" user "Package Geometry/Pastemask Top")
		(15 "B.Paste" user "Package Geometry/Pastemask Bottom")
		(5 "F.SilkS" user "Ref Des/Silkscreen Top")
		(7 "B.SilkS" user "Ref Des/Silkscreen Bottom")
		(1 "F.Mask" user "Board Geometry/Soldermask Top")
		(3 "B.Mask" user "Board Geometry/Soldermask Bottom")
		(17 "Dwgs.User" user "User.Drawings")
		(19 "Cmts.User" user "User.Comments")
		(21 "Eco1.User" user "User.Eco1")
		(23 "Eco2.User" user "User.Eco2")
		(25 "Edge.Cuts" user "Board Geometry/Outline")
		(27 "Margin" user)
		(31 "F.CrtYd" user "Package Geometry/Place Bound Top")
		(29 "B.CrtYd" user "Package Geometry/Place Bound Bottom")
		(35 "F.Fab" user "Ref Des/Assembly Top")
		(33 "B.Fab" user "Ref Des/Assembly Bottom")
	)
	(footprint ""
		(layer "F.Cu")
		(at 36.930584 -111.603282)
		(property "Reference" "C2178"
			(at 0 0 0)
			(layer "F.SilkS")
			(hide yes)
			(effects
				(font
					(size 1.27 1.27)
				)
			)
		)
		(property "Value" ""
			(at 0 0 0)
			(layer "F.Fab")
			(effects
				(font
					(size 1.27 1.27)
				)
			)
		)
		(duplicate_pad_numbers_are_jumpers no)
		(fp_line
			(start -0.7874 -0.4064)
			(end 0.7874 -0.4064)
			(stroke
				(width 0.1524)
				(type default)
			)
			(layer "F.SilkS")
		)
		(fp_line
			(start -0.7874 0.4064)
			(end -0.7874 -0.4064)
			(stroke
				(width 0.1524)
				(type default)
			)
			(layer "F.SilkS")
		)
		(fp_line
			(start 0.7874 -0.4064)
			(end 0.7874 0.4064)
			(stroke
				(width 0.1524)
				(type default)
			)
			(layer "F.SilkS")
		)
		(fp_line
			(start 0.7874 0.4064)
			(end -0.7874 0.4064)
			(stroke
				(width 0.1524)
				(type default)
			)
			(layer "F.SilkS")
		)
		(fp_line
			(start -0.67945 -0.305054)
			(end -0.12065 -0.305054)
			(stroke
				(width 0.1)
				(type default)
			)
			(layer "F.Fab")
		)
		(fp_line
			(start -0.67945 0.3048)
			(end -0.67945 -0.305054)
			(stroke
				(width 0.1)
				(type default)
			)
			(layer "F.Fab")
		)
		(fp_line
			(start -0.12065 -0.305054)
			(end -0.12065 -0.2794)
			(stroke
				(width 0.1)
				(type default)
			)
			(layer "F.Fab")
		)
		(fp_line
			(start -0.12065 -0.2794)
			(end 0.12065 -0.2794)
			(stroke
				(width 0.1)
				(type default)
			)
			(layer "F.Fab")
		)
		(fp_line
			(start -0.12065 0.2794)
			(end -0.12065 0.3048)
			(stroke
				(width 0.1)
				(type default)
			)
			(layer "F.Fab")
		)
		(fp_line
			(start -0.12065 0.3048)
			(end -0.67945 0.3048)
			(stroke
				(width 0.1)
				(type default)
			)
			(layer "F.Fab")
		)
		(fp_line
			(start 0.120396 0.2794)
			(end -0.12065 0.2794)
			(stroke
				(width 0.1)
				(type default)
			)
			(layer "F.Fab")
		)
		(fp_line
			(start 0.120396 0.3048)
			(end 0.120396 0.2794)
			(stroke
				(width 0.1)
				(type default)
			)
			(layer "F.Fab")
		)
		(fp_line
			(start 0.12065 -0.3048)
			(end 0.67945 -0.3048)
			(stroke
				(width 0.1)
				(type default)
			)
			(layer "F.Fab")
		)
		(fp_line
			(start 0.12065 -0.2794)
			(end 0.12065 -0.3048)
			(stroke
				(width 0.1)
				(type default)
			)
			(layer "F.Fab")
		)
		(fp_line
			(start 0.67945 -0.3048)
			(end 0.67945 0.3048)
			(stroke
				(width 0.1)
				(type default)
			)
			(layer "F.Fab")
		)
		(fp_line
			(start 0.67945 0.3048)
			(end 0.120396 0.3048)
			(stroke
				(width 0.1)
				(type default)
			)
			(layer "F.Fab")
		)
		(pad "1" smd circle
			(at -0.40005 0)
			(size 0 0)
			(layers "F.Cu" "F.Mask" "F.Paste")
			(net "P12V_OCP_SFF_ISENSE_TIC")
		)
		(pad "2" smd circle
			(at 0.40005 0)
			(size 0 0)
			(layers "F.Cu" "F.Mask" "F.Paste")
			(net "GND")
		)
	)
	(footprint ""
		(layer "F.Cu")
		(at 453.719946 -108.059728)
		(property "Reference" "R1905"
			(at 0 0 0)
			(layer "F.SilkS")
			(hide yes)
			(effects
				(font
					(size 1.27 1.27)
				)
			)
		)
		(property "Value" ""
			(at 0 0 0)
			(layer "F.Fab")
			(effects
				(font
					(size 1.27 1.27)
				)
			)
		)
		(duplicate_pad_numbers_are_jumpers no)
		(fp_line
			(start -0.7874 -0.4064)
			(end 0.7874 -0.4064)
			(stroke
				(width 0.1524)
				(type default)
			)
			(layer "F.SilkS")
		)
		(fp_line
			(start -0.7874 0.4064)
			(end -0.7874 -0.4064)
			(stroke
				(width 0.1524)
				(type default)
			)
			(layer "F.SilkS")
		)
		(fp_line
			(start 0.7874 -0.4064)
			(end 0.7874 0.4064)
			(stroke
				(width 0.1524)
				(type default)
			)
			(layer "F.SilkS")
		)
		(fp_line
			(start 0.7874 0.4064)
			(end -0.7874 0.4064)
			(stroke
				(width 0.1524)
				(type default)
			)
			(layer "F.SilkS")
		)
		(fp_line
			(start -0.67945 -0.305054)
			(end -0.12065 -0.305054)
			(stroke
				(width 0.1)
				(type default)
			)
			(layer "F.Fab")
		)
		(fp_line
			(start -0.67945 0.3048)
			(end -0.67945 -0.305054)
			(stroke
				(width 0.1)
				(type default)
			)
			(layer "F.Fab")
		)
		(fp_line
			(start -0.12065 -0.305054)
			(end -0.12065 -0.2794)
			(stroke
				(width 0.1)
				(type default)
			)
			(layer "F.Fab")
		)
		(fp_line
			(start -0.12065 -0.2794)
			(end 0.12065 -0.2794)
			(stroke
				(width 0.1)
				(type default)
			)
			(layer "F.Fab")
		)
		(fp_line
			(start -0.12065 0.2794)
			(end -0.12065 0.3048)
			(stroke
				(width 0.1)
				(type default)
			)
			(layer "F.Fab")
		)
		(fp_line
			(start -0.12065 0.3048)
			(end -0.67945 0.3048)
			(stroke
				(width 0.1)
				(type default)
			)
			(layer "F.Fab")
		)
		(fp_line
			(start 0.120396 0.2794)
			(end -0.12065 0.2794)
			(stroke
				(width 0.1)
				(type default)
			)
			(layer "F.Fab")
		)
		(fp_line
			(start 0.120396 0.3048)
			(end 0.120396 0.2794)
			(stroke
				(width 0.1)
				(type default)
			)
			(layer "F.Fab")
		)
		(fp_line
			(start 0.12065 -0.3048)
			(end 0.67945 -0.3048)
			(stroke
				(width 0.1)
				(type default)
			)
			(layer "F.Fab")
		)
		(fp_line
			(start 0.12065 -0.2794)
			(end 0.12065 -0.3048)
			(stroke
				(width 0.1)
				(type default)
			)
			(layer "F.Fab")
		)
		(fp_line
			(start 0.67945 -0.3048)
			(end 0.67945 0.3048)
			(stroke
				(width 0.1)
				(type default)
			)
			(layer "F.Fab")
		)
		(fp_line
			(start 0.67945 0.3048)
			(end 0.120396 0.3048)
			(stroke
				(width 0.1)
				(type default)
			)
			(layer "F.Fab")
		)
		(pad "1" smd circle
			(at -0.40005 0)
			(size 0 0)
			(layers "F.Cu" "F.Mask" "F.Paste")
			(net "P3V3_AUX")
		)
		(pad "2" smd circle
			(at 0.40005 0)
			(size 0 0)
			(layers "F.Cu" "F.Mask" "F.Paste")
			(net "OCP_SFF_PRSNT0_R_N")
		)
	)
)
